# TIMECARD (Time Appliance Project (Time Card)) — schematic netlist excerpt (pin names and nets, part order shuffled) for the footprints in the layout excerpt that follows; sources: Cadence DE-HDL packaged netlist, KiCad conversion of R4006-B0001-02_R01.brd

TP195  TP_PIONT  pkg TP010CT020B030_PTH  page 25 : \1\ = IO_L23P_35
R140  RESISTOR  0OHM -  pkg SMC_0402R_H016  page 30 : \1\ = XP1R0V_FPGA_PG ; \2\ = XP1R2V_EN_R
C61  CAPACITOR  10UF 25V 20%  pkg SMC_0805R_H057  page 21 : \1\ = XP5R0V_USB_CONN ; \2\ = SG

(kicad_pcb
	(version 20260206)
	(generator "pcbnew")
	(generator_version "10.0")
	(general
		(thickness 1.6)
		(legacy_teardrops no)
	)
	(paper "A4")
	(title_block
		(title "timecard-production-celestica-r4006 — R4006-B0001-02_R01.brd")
		(comment 1 "Time Appliance Project (Time Card) / footprints 311-313 of 1113")
	)
	(layers
		(0 "F.Cu" signal "TOP")
		(4 "In1.Cu" signal "L02_GND1")
		(6 "In2.Cu" signal "L03_SIG1")
		(8 "In3.Cu" signal "L04_GND2")
		(10 "In4.Cu" signal "L05_VCC1")
		(12 "In5.Cu" signal "L06_VCC2")
		(14 "In6.Cu" signal "L07_GND3")
		(16 "In7.Cu" signal "L08_SIG2")
		(18 "In8.Cu" signal "L09_GND4")
		(2 "B.Cu" signal "BOTTOM")
		(9 "F.Adhes" user "F.Adhesive")
		(11 "B.Adhes" user "B.Adhesive")
		(13 "F.Paste" user "Package Geometry/Pastemask Top")
		(15 "B.Paste" user "Package Geometry/Pastemask Bottom")
		(5 "F.SilkS" user "Ref Des/Silkscreen Top")
		(7 "B.SilkS" user "Ref Des/Silkscreen Bottom")
		(1 "F.Mask" user "Board Geometry/Soldermask Top")
		(3 "B.Mask" user "Board Geometry/Soldermask Bottom")
		(17 "Dwgs.User" user "User.Drawings")
		(19 "Cmts.User" user "User.Comments")
		(21 "Eco1.User" user "User.Eco1")
		(23 "Eco2.User" user "User.Eco2")
		(25 "Edge.Cuts" user "Board Geometry/Outline")
		(27 "Margin" user)
		(31 "F.CrtYd" user "Package Geometry/Place Bound Top")
		(29 "B.CrtYd" user "Package Geometry/Place Bound Bottom")
		(35 "F.Fab" user "Ref Des/Assembly Top")
		(33 "B.Fab" user "Ref Des/Assembly Bottom")
	)
	(footprint ""
		(layer "F.Cu")
		(at 158.115 -50.894996 -90)
		(property "Reference" "C61"
			(at -0.794004 2.50063 90)
			(unlocked yes)
			(layer "F.SilkS")
			(effects
				(font
					(size 0.7874 0.5842)
					(thickness 0.1524)
				)
			)
		)
		(property "Value" "VAL*"
			(at 0.0762 3.134106 270)
			(unlocked yes)
			(layer "F.Fab")
			(hide yes)
			(effects
				(font
					(size 0.7874 0.5842)
					(thickness 0.1524)
				)
			)
		)
		(property "Tolerance" "TOL*"
			(at 0.0762 4.048506 270)
			(unlocked yes)
			(layer "Cmts.User")
			(hide yes)
			(effects
				(font
					(size 0.7874 0.5842)
					(thickness 0.1524)
				)
			)
		)
		(property "User Part Number" "PARTNUM*"
			(at 0.1016 5.013706 270)
			(unlocked yes)
			(layer "Cmts.User")
			(hide yes)
			(effects
				(font
					(size 0.7874 0.5842)
					(thickness 0.1524)
				)
			)
		)
		(property "Device Type" "CAPACITOR-G107-0F106-EM,10UF,2A"
			(at 0.0508 2.194306 270)
			(unlocked yes)
			(layer "F.Fab")
			(hide yes)
			(effects
				(font
					(size 0.7874 0.5842)
					(thickness 0.1524)
				)
			)
		)
		(duplicate_pad_numbers_are_jumpers no)
		(fp_line
			(start -1.5748 0.9398)
			(end 1.5748 0.9398)
			(stroke
				(width 0.1)
				(type default)
			)
			(layer "F.SilkS")
		)
		(fp_line
			(start 1.5748 0.9398)
			(end 1.5748 -0.9398)
			(stroke
				(width 0.1)
				(type default)
			)
			(layer "F.SilkS")
		)
		(fp_line
			(start -1.5748 -0.9398)
			(end -1.5748 0.9398)
			(stroke
				(width 0.1)
				(type default)
			)
			(layer "F.SilkS")
		)
		(fp_line
			(start 1.5748 -0.9398)
			(end -1.5748 -0.9398)
			(stroke
				(width 0.1)
				(type default)
			)
			(layer "F.SilkS")
		)
		(fp_rect
			(start 1.5748 -0.9398)
			(end -1.5748 0.9398)
			(stroke
				(width 0)
				(type default)
			)
			(fill no)
			(layer "F.CrtYd")
		)
		(fp_line
			(start -1.016 0.635)
			(end 1.016 0.635)
			(stroke
				(width 0.1)
				(type default)
			)
			(layer "F.Fab")
		)
		(fp_line
			(start 1.016 0.635)
			(end 1.016 -0.635)
			(stroke
				(width 0.1)
				(type default)
			)
			(layer "F.Fab")
		)
		(fp_line
			(start -1.016 -0.635)
			(end -1.016 0.635)
			(stroke
				(width 0.1)
				(type default)
			)
			(layer "F.Fab")
		)
		(fp_line
			(start 1.016 -0.635)
			(end -1.016 -0.635)
			(stroke
				(width 0.1)
				(type default)
			)
			(layer "F.Fab")
		)
		(pad "1" smd rect
			(at -0.8382 0 270)
			(size 0.9652 1.3716)
			(layers "F.Cu" "F.Mask" "F.Paste")
			(net "XP5R0V_USB_CONN")
		)
		(pad "2" smd rect
			(at 0.8382 0 270)
			(size 0.9652 1.3716)
			(layers "F.Cu" "F.Mask" "F.Paste")
			(net "SG")
		)
		(zone
			(layer "F.Cu")
			(hatch none 0.5)
			(connect_pads
				(clearance 0)
			)
			(min_thickness 0.25)
			(keepout
				(tracks allowed)
				(vias not_allowed)
				(pads allowed)
				(copperpour not_allowed)
				(footprints allowed)
			)
			(placement
				(enabled no)
				(sheetname "")
			)
			(fill
				(thermal_gap 0.5)
				(thermal_bridge_width 0.5)
				(island_removal_mode 0)
			)
			(polygon
				(pts
					(xy 158.75 -50.666396) (xy 158.75 -51.123596) (xy 157.48 -51.123596) (xy 157.48 -50.666396)
				)
			)
		)
	)
	(footprint ""
		(layer "F.Cu")
		(at 105.41 -31.369 90)
		(property "Reference" "TP195"
			(at 0 0 90)
			(layer "F.SilkS")
			(hide yes)
			(effects
				(font
					(size 1.27 1.27)
				)
			)
		)
		(property "Value" ""
			(at 0 0 90)
			(layer "F.Fab")
			(effects
				(font
					(size 1.27 1.27)
				)
			)
		)
		(property "Device Type" "TP_PIONT-TP010CT020B030_PTH-TPA"
			(at -1.341882 0.996696 90)
			(unlocked yes)
			(layer "F.Fab")
			(hide yes)
			(effects
				(font
					(size 0.7874 0.5842)
					(thickness 0.1524)
				)
				(justify left)
			)
		)
		(duplicate_pad_numbers_are_jumpers no)
		(fp_poly
			(pts
				(arc
					(start 0 0.889)
					(mid 0 -0.889)
					(end 0 0.889)
				)
			)
			(stroke
				(width 0)
				(type default)
			)
			(fill no)
			(layer "B.CrtYd")
		)
		(fp_poly
			(pts
				(arc
					(start 0 0.889)
					(mid 0 -0.889)
					(end 0 0.889)
				)
			)
			(stroke
				(width 0)
				(type default)
			)
			(fill no)
			(layer "F.CrtYd")
		)
		(pad "1" thru_hole circle
			(at 0 0 90)
			(size 0.508 0.508)
			(drill 0.254)
			(layers "*.Cu" "*.Mask")
			(remove_unused_layers no)
			(net "IO_L23P_35")
			(clearance 0.1016)
			(padstack
				(mode front_inner_back)
				(layer "Inner"
					(shape circle)
					(size 0.508 0.508)
					(clearance 0.1016)
				)
				(layer "B.Cu"
					(shape circle)
					(size 0.762 0.762)
					(clearance -0.0254)
				)
			)
		)
	)
	(footprint ""
		(layer "F.Cu")
		(at 96.8756 -78.5368)
		(property "Reference" "R140"
			(at 0.0254 -1.17983 0)
			(unlocked yes)
			(layer "F.SilkS")
			(effects
				(font
					(size 0.7874 0.5842)
					(thickness 0.1524)
				)
			)
		)
		(property "Value" "VAL*"
			(at 0.02032 2.13233 0)
			(unlocked yes)
			(layer "F.Fab")
			(hide yes)
			(effects
				(font
					(size 0.7874 0.5842)
					(thickness 0.1524)
				)
			)
		)
		(property "Device Type" "RESISTOR-G155-100R0-J0,0OHM,-"
			(at 0.008382 1.210564 0)
			(unlocked yes)
			(layer "F.Fab")
			(hide yes)
			(effects
				(font
					(size 0.7874 0.5842)
					(thickness 0.1524)
				)
			)
		)
		(property "User Part Number" "PARTNUM*"
			(at 0.02032 4.024884 0)
			(unlocked yes)
			(layer "Cmts.User")
			(hide yes)
			(effects
				(font
					(size 0.7874 0.5842)
					(thickness 0.1524)
				)
			)
		)
		(property "Tolerance" "TOL*"
			(at 0.044704 3.05435 0)
			(unlocked yes)
			(layer "Cmts.User")
			(hide yes)
			(effects
				(font
					(size 0.7874 0.5842)
					(thickness 0.1524)
				)
			)
		)
		(duplicate_pad_numbers_are_jumpers no)
		(fp_line
			(start -1.143 -0.5588)
			(end -1.143 0.5588)
			(stroke
				(width 0.1)
				(type default)
			)
			(layer "F.SilkS")
		)
		(fp_line
			(start -1.143 0.5588)
			(end 1.143 0.5588)
			(stroke
				(width 0.1)
				(type default)
			)
			(layer "F.SilkS")
		)
		(fp_line
			(start 1.143 -0.5588)
			(end -1.143 -0.5588)
			(stroke
				(width 0.1)
				(type default)
			)
			(layer "F.SilkS")
		)
		(fp_line
			(start 1.143 0.5588)
			(end 1.143 -0.5588)
			(stroke
				(width 0.1)
				(type default)
			)
			(layer "F.SilkS")
		)
		(fp_rect
			(start -1.143 -0.5588)
			(end 1.143 0.5588)
			(stroke
				(width 0)
				(type default)
			)
			(fill no)
			(layer "F.CrtYd")
		)
		(fp_line
			(start -0.508 -0.3048)
			(end -0.508 0.3048)
			(stroke
				(width 0.1)
				(type default)
			)
			(layer "F.Fab")
		)
		(fp_line
			(start -0.508 0.3048)
			(end 0.508 0.3048)
			(stroke
				(width 0.1)
				(type default)
			)
			(layer "F.Fab")
		)
		(fp_line
			(start 0.508 -0.3048)
			(end -0.508 -0.3048)
			(stroke
				(width 0.1)
				(type default)
			)
			(layer "F.Fab")
		)
		(fp_line
			(start 0.508 0.3048)
			(end 0.508 -0.3048)
			(stroke
				(width 0.1)
				(type default)
			)
			(layer "F.Fab")
		)
		(pad "1" smd rect
			(at -0.5334 0)
			(size 0.7112 0.6096)
			(layers "F.Cu" "F.Mask" "F.Paste")
			(net "XP1R0V_FPGA_PG")
		)
		(pad "2" smd rect
			(at 0.5334 0)
			(size 0.7112 0.6096)
			(layers "F.Cu" "F.Mask" "F.Paste")
			(net "XP1R2V_EN_R")
		)
		(zone
			(layer "F.Cu")
			(hatch none 0.5)
			(connect_pads
				(clearance 0)
			)
			(min_thickness 0.25)
			(keepout
				(tracks allowed)
				(vias not_allowed)
				(pads allowed)
				(copperpour not_allowed)
				(footprints allowed)
			)
			(placement
				(enabled no)
				(sheetname "")
			)
			(fill
				(thermal_gap 0.5)
				(thermal_bridge_width 0.5)
				(island_removal_mode 0)
			)
			(polygon
				(pts
					(xy 96.7994 -78.8416) (xy 96.7994 -78.232) (xy 96.9518 -78.232) (xy 96.9518 -78.8416)
				)
			)
		)
	)
)
